# T6G (Grand Teton) — schematic netlist excerpt (pin names and nets, part order shuffled) for the footprints in the layout excerpt that follows; sources: Cadence DE-HDL packaged netlist, KiCad conversion of 04192023_DAF0TMB3IC0_F0TG_MB_C_brd_V02_OCP.brd

PC8  Q_CAP  0.1UF 25V 10% X7R  pkg 0402  page 224 : A = PVDD11_S3_P1_VINSEN ; B = GND
PR3914  Q_RES  2K 0.1% CHIP  pkg 0402LF  page 263 : A = HSC_CS_1 ; B = AGND_HSC

(kicad_pcb
	(version 20260206)
	(generator "pcbnew")
	(generator_version "10.0")
	(general
		(thickness 1.6)
		(legacy_teardrops no)
	)
	(paper "A4")
	(title_block
		(title "04192023_DAF0TMB3IC0_F0TG_MB_C_brd_V02_OCP.brd")
		(comment 1 "Grand Teton / footprints 2083-2084 of 8354")
	)
	(layers
		(0 "F.Cu" signal "TOP")
		(4 "In1.Cu" signal "GND")
		(6 "In2.Cu" signal "IN1")
		(8 "In3.Cu" signal "GND1")
		(10 "In4.Cu" signal "IN2")
		(12 "In5.Cu" signal "GND2")
		(14 "In6.Cu" signal "IN3")
		(16 "In7.Cu" signal "GND3")
		(18 "In8.Cu" signal "VCC")
		(20 "In9.Cu" signal "VCC1")
		(22 "In10.Cu" signal "GND4")
		(24 "In11.Cu" signal "IN4")
		(26 "In12.Cu" signal "GND5")
		(28 "In13.Cu" signal "IN5")
		(30 "In14.Cu" signal "GND6")
		(32 "In15.Cu" signal "IN6")
		(34 "In16.Cu" signal "GND7")
		(2 "B.Cu" signal "BOTTOM")
		(9 "F.Adhes" user "F.Adhesive")
		(11 "B.Adhes" user "B.Adhesive")
		(13 "F.Paste" user "Package Geometry/Pastemask Top")
		(15 "B.Paste" user "Package Geometry/Pastemask Bottom")
		(5 "F.SilkS" user "Ref Des/Silkscreen Top")
		(7 "B.SilkS" user "Ref Des/Silkscreen Bottom")
		(1 "F.Mask" user "Board Geometry/Soldermask Top")
		(3 "B.Mask" user "Board Geometry/Soldermask Bottom")
		(17 "Dwgs.User" user "User.Drawings")
		(19 "Cmts.User" user "User.Comments")
		(21 "Eco1.User" user "User.Eco1")
		(23 "Eco2.User" user "User.Eco2")
		(25 "Edge.Cuts" user "Board Geometry/Outline")
		(27 "Margin" user)
		(31 "F.CrtYd" user "Package Geometry/Place Bound Top")
		(29 "B.CrtYd" user "Package Geometry/Place Bound Bottom")
		(35 "F.Fab" user "Ref Des/Assembly Top")
		(33 "B.Fab" user "Ref Des/Assembly Bottom")
	)
	(footprint ""
		(layer "F.Cu")
		(at 194.2211 -399.982182 180)
		(property "Reference" "PR3914"
			(at 0 0 180)
			(layer "F.SilkS")
			(hide yes)
			(effects
				(font
					(size 1.27 1.27)
				)
			)
		)
		(property "Value" ""
			(at 0 0 180)
			(layer "F.Fab")
			(effects
				(font
					(size 1.27 1.27)
				)
			)
		)
		(duplicate_pad_numbers_are_jumpers no)
		(fp_line
			(start 0.7874 0.4064)
			(end -0.7874 0.4064)
			(stroke
				(width 0.1524)
				(type default)
			)
			(layer "F.SilkS")
		)
		(fp_line
			(start 0.7874 -0.4064)
			(end 0.7874 0.4064)
			(stroke
				(width 0.1524)
				(type default)
			)
			(layer "F.SilkS")
		)
		(fp_line
			(start -0.7874 0.4064)
			(end -0.7874 -0.4064)
			(stroke
				(width 0.1524)
				(type default)
			)
			(layer "F.SilkS")
		)
		(fp_line
			(start -0.7874 -0.4064)
			(end 0.7874 -0.4064)
			(stroke
				(width 0.1524)
				(type default)
			)
			(layer "F.SilkS")
		)
		(fp_line
			(start 0.67945 0.3048)
			(end 0.120396 0.3048)
			(stroke
				(width 0.1)
				(type default)
			)
			(layer "F.Fab")
		)
		(fp_line
			(start 0.67945 -0.3048)
			(end 0.67945 0.3048)
			(stroke
				(width 0.1)
				(type default)
			)
			(layer "F.Fab")
		)
		(fp_line
			(start 0.12065 -0.2794)
			(end 0.12065 -0.3048)
			(stroke
				(width 0.1)
				(type default)
			)
			(layer "F.Fab")
		)
		(fp_line
			(start 0.12065 -0.3048)
			(end 0.67945 -0.3048)
			(stroke
				(width 0.1)
				(type default)
			)
			(layer "F.Fab")
		)
		(fp_line
			(start 0.120396 0.3048)
			(end 0.120396 0.2794)
			(stroke
				(width 0.1)
				(type default)
			)
			(layer "F.Fab")
		)
		(fp_line
			(start 0.120396 0.2794)
			(end -0.12065 0.2794)
			(stroke
				(width 0.1)
				(type default)
			)
			(layer "F.Fab")
		)
		(fp_line
			(start -0.12065 0.3048)
			(end -0.67945 0.3048)
			(stroke
				(width 0.1)
				(type default)
			)
			(layer "F.Fab")
		)
		(fp_line
			(start -0.12065 0.2794)
			(end -0.12065 0.3048)
			(stroke
				(width 0.1)
				(type default)
			)
			(layer "F.Fab")
		)
		(fp_line
			(start -0.12065 -0.2794)
			(end 0.12065 -0.2794)
			(stroke
				(width 0.1)
				(type default)
			)
			(layer "F.Fab")
		)
		(fp_line
			(start -0.12065 -0.305054)
			(end -0.12065 -0.2794)
			(stroke
				(width 0.1)
				(type default)
			)
			(layer "F.Fab")
		)
		(fp_line
			(start -0.67945 0.3048)
			(end -0.67945 -0.305054)
			(stroke
				(width 0.1)
				(type default)
			)
			(layer "F.Fab")
		)
		(fp_line
			(start -0.67945 -0.305054)
			(end -0.12065 -0.305054)
			(stroke
				(width 0.1)
				(type default)
			)
			(layer "F.Fab")
		)
		(pad "1" smd circle
			(at -0.40005 0 180)
			(size 0 0)
			(layers "F.Cu" "F.Mask" "F.Paste")
			(net "HSC_CS_1")
		)
		(pad "2" smd circle
			(at 0.40005 0 180)
			(size 0 0)
			(layers "F.Cu" "F.Mask" "F.Paste")
			(net "AGND_HSC")
		)
	)
	(footprint ""
		(layer "F.Cu")
		(at 166.920672 -350.248474)
		(property "Reference" "PC8"
			(at 0 0 0)
			(layer "F.SilkS")
			(hide yes)
			(effects
				(font
					(size 1.27 1.27)
				)
			)
		)
		(property "Value" ""
			(at 0 0 0)
			(layer "F.Fab")
			(effects
				(font
					(size 1.27 1.27)
				)
			)
		)
		(duplicate_pad_numbers_are_jumpers no)
		(fp_line
			(start -0.7874 -0.4064)
			(end 0.7874 -0.4064)
			(stroke
				(width 0.1524)
				(type default)
			)
			(layer "F.SilkS")
		)
		(fp_line
			(start -0.7874 0.4064)
			(end -0.7874 -0.4064)
			(stroke
				(width 0.1524)
				(type default)
			)
			(layer "F.SilkS")
		)
		(fp_line
			(start 0.7874 -0.4064)
			(end 0.7874 0.4064)
			(stroke
				(width 0.1524)
				(type default)
			)
			(layer "F.SilkS")
		)
		(fp_line
			(start 0.7874 0.4064)
			(end -0.7874 0.4064)
			(stroke
				(width 0.1524)
				(type default)
			)
			(layer "F.SilkS")
		)
		(fp_line
			(start -0.67945 -0.305054)
			(end -0.12065 -0.305054)
			(stroke
				(width 0.1)
				(type default)
			)
			(layer "F.Fab")
		)
		(fp_line
			(start -0.67945 0.3048)
			(end -0.67945 -0.305054)
			(stroke
				(width 0.1)
				(type default)
			)
			(layer "F.Fab")
		)
		(fp_line
			(start -0.12065 -0.305054)
			(end -0.12065 -0.2794)
			(stroke
				(width 0.1)
				(type default)
			)
			(layer "F.Fab")
		)
		(fp_line
			(start -0.12065 -0.2794)
			(end 0.12065 -0.2794)
			(stroke
				(width 0.1)
				(type default)
			)
			(layer "F.Fab")
		)
		(fp_line
			(start -0.12065 0.2794)
			(end -0.12065 0.3048)
			(stroke
				(width 0.1)
				(type default)
			)
			(layer "F.Fab")
		)
		(fp_line
			(start -0.12065 0.3048)
			(end -0.67945 0.3048)
			(stroke
				(width 0.1)
				(type default)
			)
			(layer "F.Fab")
		)
		(fp_line
			(start 0.120396 0.2794)
			(end -0.12065 0.2794)
			(stroke
				(width 0.1)
				(type default)
			)
			(layer "F.Fab")
		)
		(fp_line
			(start 0.120396 0.3048)
			(end 0.120396 0.2794)
			(stroke
				(width 0.1)
				(type default)
			)
			(layer "F.Fab")
		)
		(fp_line
			(start 0.12065 -0.3048)
			(end 0.67945 -0.3048)
			(stroke
				(width 0.1)
				(type default)
			)
			(layer "F.Fab")
		)
		(fp_line
			(start 0.12065 -0.2794)
			(end 0.12065 -0.3048)
			(stroke
				(width 0.1)
				(type default)
			)
			(layer "F.Fab")
		)
		(fp_line
			(start 0.67945 -0.3048)
			(end 0.67945 0.3048)
			(stroke
				(width 0.1)
				(type default)
			)
			(layer "F.Fab")
		)
		(fp_line
			(start 0.67945 0.3048)
			(end 0.120396 0.3048)
			(stroke
				(width 0.1)
				(type default)
			)
			(layer "F.Fab")
		)
		(pad "1" smd circle
			(at -0.40005 0)
			(size 0 0)
			(layers "F.Cu" "F.Mask" "F.Paste")
			(net "PVDD11_S3_P1_VINSEN")
		)
		(pad "2" smd circle
			(at 0.40005 0)
			(size 0 0)
			(layers "F.Cu" "F.Mask" "F.Paste")
			(net "GND")
		)
	)
)
